(kicad_pcb
	(version 20211014)
	(generator pcbnew)
	(general
    (thickness 1.6)
  )
	(paper "A4")
	(title_block
    (title "SA800U (Snapdragon 845) Baseboard")
    (date "2023-10-19")
    (rev "1.0.3")
    (company "Antmicro Ltd.")
    (comment 1 "www.antmicro.com")
		(comment 9 "footprints 8-13 of 589")
	)
	(layers
    (0 "F.Cu" signal)
    (1 "In1.Cu" power)
    (2 "In2.Cu" signal)
    (3 "In3.Cu" signal)
    (4 "In4.Cu" power)
    (31 "B.Cu" signal)
    (32 "B.Adhes" user "B.Adhesive")
    (33 "F.Adhes" user "F.Adhesive")
    (34 "B.Paste" user)
    (35 "F.Paste" user)
    (36 "B.SilkS" user "B.Silkscreen")
    (37 "F.SilkS" user "F.Silkscreen")
    (38 "B.Mask" user)
    (39 "F.Mask" user)
    (40 "Dwgs.User" user "User.Drawings")
    (41 "Cmts.User" user "User.Comments")
    (42 "Eco1.User" user "User.Eco1")
    (43 "Eco2.User" user "User.Eco2")
    (44 "Edge.Cuts" user)
    (45 "Margin" user)
    (46 "B.CrtYd" user "B.Courtyard")
    (47 "F.CrtYd" user "F.Courtyard")
    (48 "B.Fab" user)
    (49 "F.Fab" user)
  )
	(footprint "sa800u-baseboard-hw-footprints:SW_SPST_4.2x2.8" (layer "F.Cu")
    (tedit 5DF0C83F)
    (at 152 111.5)
    (descr "KMR211G")
    (tags "SPST Button Switch")
    (property "Author" "Antmicro")
    (property "License" "Apache-2.0")
    (property "MPN" "KMR211NGLFS")
    (property "Manufacturer" "C&K")
    (property "Sheetfile" "som.kicad_sch")
    (property "Sheetname" "SoM")
    (attr smd)
    (fp_text reference "S3" (at 1.41 2.66) (layer "F.SilkS")
      (effects (font (size 0.7 0.7) (thickness 0.15)) (justify left bottom))
    )
    (fp_text value "SW_SPST_KMR211NGLFS" (at -3 3) (layer "F.Fab")
      (effects (font (size 0.7 0.7) (thickness 0.15)) (justify left bottom))
    )
    (fp_text user "License: Apache-2.0" (at -3 6.75) (layer "F.Fab") hide
      (effects (font (size 0.7 0.7) (thickness 0.15)) (justify left bottom))
    )
    (fp_text user "${REFERENCE}" (at -3 4.25) (layer "F.Fab") hide
      (effects (font (size 0.7 0.7) (thickness 0.15)) (justify left bottom))
    )
    (fp_text user "Author: Antmicro" (at -3 5.5) (layer "F.Fab") hide
      (effects (font (size 0.7 0.7) (thickness 0.15)) (justify left bottom))
    )
    (fp_line (start -2.101 -1.601) (end 2.1 -1.601) (layer "F.SilkS") (width 0.15))
    (fp_line (start 2.1 1.6) (end 2.1 1.499) (layer "F.SilkS") (width 0.15))
    (fp_line (start -2.101 1.58) (end -2.101 1.459) (layer "F.SilkS") (width 0.15))
    (fp_line (start -2.101 1.6) (end 2.1 1.6) (layer "F.SilkS") (width 0.15))
    (fp_line (start 2.1 -1.601) (end 2.1 -1.48) (layer "F.SilkS") (width 0.15))
    (fp_line (start -2.101 -1.601) (end -2.101 -1.48) (layer "F.SilkS") (width 0.15))
    (fp_rect (start -2.751 -1.75) (end 2.748 1.749) (layer "F.CrtYd") (width 0.05) (fill none))
    (fp_line (start -0.25 -0.802) (end 0.248 -0.802) (layer "F.Fab") (width 0.15))
    (fp_line (start 2.1 -1.601) (end -2.101 -1.601) (layer "F.Fab") (width 0.15))
    (fp_line (start 2.1 1.6) (end 2.1 -1.601) (layer "F.Fab") (width 0.15))
    (fp_line (start -2.101 -1.601) (end -2.101 1.6) (layer "F.Fab") (width 0.15))
    (fp_line (start -2.101 1.6) (end 2.1 1.6) (layer "F.Fab") (width 0.15))
    (fp_line (start 0.248 0.8) (end -0.25 0.8) (layer "F.Fab") (width 0.15))
    (fp_arc (start -0.25 0.8) (mid -1.051001 -0.001) (end -0.25 -0.802) (layer "F.Fab") (width 0.15))
    (fp_arc (start 0.248 -0.802) (mid 1.050001 -0.001) (end 0.248 0.8) (layer "F.Fab") (width 0.15))
    (pad "1" smd rect (at 2.048 -0.802) (size 0.9 1) (layers "F.Cu" "F.Paste" "F.Mask")
      (net 1 "GND") (pintype "passive"))
    (pad "2" smd rect (at 2.048 0.8) (size 0.9 1) (layers "F.Cu" "F.Paste" "F.Mask")
      (net 346 "/SoM/PWR_R") (pintype "passive"))
    (pad "3" smd rect (at -2.05 -0.802) (size 0.9 1) (layers "F.Cu" "F.Paste" "F.Mask")
      (net 1 "GND") (pintype "passive"))
    (pad "4" smd rect (at -2.05 0.8) (size 0.9 1) (layers "F.Cu" "F.Paste" "F.Mask")
      (net 346 "/SoM/PWR_R") (pintype "passive"))
  )
	(footprint "sa800u-baseboard-hw-footprints:SW_SPST_4.2x2.8" (layer "F.Cu")
    (tedit 5DF0C83F)
    (at 152 105.5)
    (descr "KMR211G")
    (tags "SPST Button Switch")
    (property "Author" "Antmicro")
    (property "License" "Apache-2.0")
    (property "MPN" "KMR211NGLFS")
    (property "Manufacturer" "C&K")
    (property "Sheetfile" "som.kicad_sch")
    (property "Sheetname" "SoM")
    (attr smd)
    (fp_text reference "S4" (at -2.45 -1.91) (layer "F.SilkS")
      (effects (font (size 0.7 0.7) (thickness 0.15)) (justify left bottom))
    )
    (fp_text value "SW_SPST_KMR211NGLFS" (at -3 3) (layer "F.Fab")
      (effects (font (size 0.7 0.7) (thickness 0.15)) (justify left bottom))
    )
    (fp_text user "License: Apache-2.0" (at -3 6.75) (layer "F.Fab") hide
      (effects (font (size 0.7 0.7) (thickness 0.15)) (justify left bottom))
    )
    (fp_text user "${REFERENCE}" (at -3 4.25) (layer "F.Fab") hide
      (effects (font (size 0.7 0.7) (thickness 0.15)) (justify left bottom))
    )
    (fp_text user "Author: Antmicro" (at -3 5.5) (layer "F.Fab") hide
      (effects (font (size 0.7 0.7) (thickness 0.15)) (justify left bottom))
    )
    (fp_line (start -2.101 -1.601) (end -2.101 -1.48) (layer "F.SilkS") (width 0.15))
    (fp_line (start -2.101 -1.601) (end 2.1 -1.601) (layer "F.SilkS") (width 0.15))
    (fp_line (start -2.101 1.58) (end -2.101 1.459) (layer "F.SilkS") (width 0.15))
    (fp_line (start 2.1 -1.601) (end 2.1 -1.48) (layer "F.SilkS") (width 0.15))
    (fp_line (start 2.1 1.6) (end 2.1 1.499) (layer "F.SilkS") (width 0.15))
    (fp_line (start -2.101 1.6) (end 2.1 1.6) (layer "F.SilkS") (width 0.15))
    (fp_rect (start -2.751 -1.75) (end 2.748 1.749) (layer "F.CrtYd") (width 0.05) (fill none))
    (fp_line (start 2.1 -1.601) (end -2.101 -1.601) (layer "F.Fab") (width 0.15))
    (fp_line (start -2.101 -1.601) (end -2.101 1.6) (layer "F.Fab") (width 0.15))
    (fp_line (start 0.248 0.8) (end -0.25 0.8) (layer "F.Fab") (width 0.15))
    (fp_line (start -0.25 -0.802) (end 0.248 -0.802) (layer "F.Fab") (width 0.15))
    (fp_line (start -2.101 1.6) (end 2.1 1.6) (layer "F.Fab") (width 0.15))
    (fp_line (start 2.1 1.6) (end 2.1 -1.601) (layer "F.Fab") (width 0.15))
    (fp_arc (start 0.248 -0.802) (mid 1.050001 -0.001) (end 0.248 0.8) (layer "F.Fab") (width 0.15))
    (fp_arc (start -0.25 0.8) (mid -1.051001 -0.001) (end -0.25 -0.802) (layer "F.Fab") (width 0.15))
    (pad "1" smd rect (at 2.048 -0.802) (size 0.9 1) (layers "F.Cu" "F.Paste" "F.Mask")
      (net 1 "GND") (pintype "passive"))
    (pad "2" smd rect (at 2.048 0.8) (size 0.9 1) (layers "F.Cu" "F.Paste" "F.Mask")
      (net 343 "/SoM/VOL_DOWN_R") (pintype "passive"))
    (pad "3" smd rect (at -2.05 -0.802) (size 0.9 1) (layers "F.Cu" "F.Paste" "F.Mask")
      (net 1 "GND") (pintype "passive"))
    (pad "4" smd rect (at -2.05 0.8) (size 0.9 1) (layers "F.Cu" "F.Paste" "F.Mask")
      (net 343 "/SoM/VOL_DOWN_R") (pintype "passive"))
  )
	(footprint "sa800u-baseboard-hw-footprints:HDMI_Micro-D_Molex_46765-1x01" locked (layer "F.Cu")
    (tedit 615AA2CD)
    (at 144.251 149.001)
    (descr "HDMI, Micro, Type D, THT, 0.4mm pitch, 19 ckt, right angle (http://www.molex.com/pdm_docs/sd/467651301_sd.pdf)")
    (tags "hdmi micro type d right angle tht")
    (property "Author" "Antmicro")
    (property "License" "Apache-2.0")
    (property "MPN" "467651001")
    (property "Manufacturer" "Molex")
    (property "Sheetfile" "hdmi-converter.kicad_sch")
    (property "Sheetname" "HDMI converter")
    (attr smd)
    (fp_text reference "J2" (at 3.499 -3.501) (layer "F.SilkS")
      (effects (font (size 0.7 0.7) (thickness 0.15)) (justify left bottom))
    )
    (fp_text value "HDMI_Micro-D_46756-1001" (at -3.4 5) (layer "F.Fab")
      (effects (font (size 0.7 0.7) (thickness 0.15)) (justify left bottom))
    )
    (fp_text user "License: Apache-2.0" (at -3.4 9) (layer "F.Fab") hide
      (effects (font (size 0.7 0.7) (thickness 0.15)) (justify left bottom))
    )
    (fp_text user "${REFERENCE}" (at -3.4 6.4) (layer "F.Fab") hide
      (effects (font (size 0.7 0.7) (thickness 0.15)) (justify left bottom))
    )
    (fp_text user "Author: Antmicro" (at -3.4 7.6) (layer "F.Fab") hide
      (effects (font (size 0.7 0.7) (thickness 0.15)) (justify left bottom))
    )
    (fp_line (start 3.309 -3.86) (end 3.309 -3.551) (layer "F.SilkS") (width 0.15))
    (fp_line (start -3.31 -3.551) (end -3.31 -3.86) (layer "F.SilkS") (width 0.15))
    (fp_line (start -3.31 -3.86) (end -2.15 -3.86) (layer "F.SilkS") (width 0.15))
    (fp_line (start -3.31 -0.201) (end -3.31 -0.6) (layer "F.SilkS") (width 0.15))
    (fp_line (start -3.301 2.899) (end -3.301 2.499) (layer "F.SilkS") (width 0.15))
    (fp_line (start 3.309 2.499) (end 3.309 2.899) (layer "F.SilkS") (width 0.15))
    (fp_line (start 2.148 -3.86) (end 3.309 -3.86) (layer "F.SilkS") (width 0.15))
    (fp_line (start 3.309 -0.6) (end 3.309 -0.201) (layer "F.SilkS") (width 0.15))
    (fp_line (start 2.148 -3.86) (end 2.148 -4.061) (layer "F.SilkS") (width 0.15))
    (fp_rect (start -3.45 -4.101) (end 3.45 3.949) (layer "F.CrtYd") (width 0.05) (fill none))
    (fp_line (start 1.8 -3.301) (end 1.3 -3.801) (layer "B.Fab") (width 0.15))
    (fp_line (start 3.249 3.7) (end -3.25 3.7) (layer "F.Fab") (width 0.15))
    (fp_line (start -3.25 -3.801) (end 1.3 -3.801) (layer "F.Fab") (width 0.15))
    (fp_line (start 3.249 -3.801) (end 3.249 3.7) (layer "F.Fab") (width 0.15))
    (fp_line (start 2.298 -3.801) (end 3.249 -3.801) (layer "F.Fab") (width 0.15))
    (fp_line (start 1.8 -3.301) (end 2.298 -3.801) (layer "F.Fab") (width 0.15))
    (fp_line (start -3.25 3.7) (end -3.25 -3.801) (layer "F.Fab") (width 0.15))
    (pad "1" smd rect locked (at 1.8 -3.476) (size 0.23 0.85) (layers "F.Cu" "F.Paste" "F.Mask")
      (net 234 "/HDMI converter/HDMI_DETECT") (pinfunction "HPD/HEAC-") (pintype "passive"))
    (pad "2" smd rect locked (at 1.6 -2.25) (size 0.23 1) (layers "F.Cu" "F.Paste" "F.Mask")
      (net 414 "unconnected-(J2-Pad2)") (pinfunction "UTILITY/HEAC+") (pintype "passive+no_connect"))
    (pad "3" smd rect locked (at 1.398 -3.476) (size 0.23 0.85) (layers "F.Cu" "F.Paste" "F.Mask")
      (net 243 "/HDMI converter/HDMI_TX2_CONN_P") (pinfunction "D2+") (pintype "passive"))
    (pad "4" smd rect locked (at 1.199 -2.25) (size 0.23 1) (layers "F.Cu" "F.Paste" "F.Mask")
      (net 1 "GND") (pinfunction "D2S") (pintype "power_in"))
    (pad "5" smd rect locked (at 0.998 -3.476) (size 0.23 0.85) (layers "F.Cu" "F.Paste" "F.Mask")
      (net 240 "/HDMI converter/HDMI_TX2_CONN_N") (pinfunction "D2-") (pintype "passive"))
    (pad "6" smd rect locked (at 0.8 -2.25) (size 0.23 1) (layers "F.Cu" "F.Paste" "F.Mask")
      (net 241 "/HDMI converter/HDMI_TX1_CONN_P") (pinfunction "D1+") (pintype "passive"))
    (pad "7" smd rect locked (at 0.598 -3.476) (size 0.23 0.85) (layers "F.Cu" "F.Paste" "F.Mask")
      (net 1 "GND") (pinfunction "D1S") (pintype "power_in"))
    (pad "8" smd rect locked (at 0.4 -2.25) (size 0.23 1) (layers "F.Cu" "F.Paste" "F.Mask")
      (net 242 "/HDMI converter/HDMI_TX1_CONN_N") (pinfunction "D1-") (pintype "passive"))
    (pad "9" smd rect locked (at 0.2 -3.476) (size 0.23 0.85) (layers "F.Cu" "F.Paste" "F.Mask")
      (net 239 "/HDMI converter/HDMI_TX0_CONN_P") (pinfunction "D0+") (pintype "passive"))
    (pad "10" smd rect locked (at 0 -2.25) (size 0.23 1) (layers "F.Cu" "F.Paste" "F.Mask")
      (net 1 "GND") (pinfunction "D0S") (pintype "power_in"))
    (pad "11" smd rect locked (at -0.202 -3.476) (size 0.23 0.85) (layers "F.Cu" "F.Paste" "F.Mask")
      (net 236 "/HDMI converter/HDMI_TX0_CONN_N") (pinfunction "D0-") (pintype "passive"))
    (pad "12" smd rect locked (at -0.402 -2.25) (size 0.23 1) (layers "F.Cu" "F.Paste" "F.Mask")
      (net 237 "/HDMI converter/HDMI_CLK_CONN_P") (pinfunction "CK+") (pintype "passive"))
    (pad "13" smd rect locked (at -0.6 -3.476) (size 0.23 0.85) (layers "F.Cu" "F.Paste" "F.Mask")
      (net 1 "GND") (pinfunction "CKS") (pintype "power_in"))
    (pad "14" smd rect locked (at -0.802 -2.25) (size 0.23 1) (layers "F.Cu" "F.Paste" "F.Mask")
      (net 238 "/HDMI converter/HDMI_CLK_CONN_N") (pinfunction "CK-") (pintype "passive"))
    (pad "15" smd rect locked (at -1 -3.476) (size 0.23 0.85) (layers "F.Cu" "F.Paste" "F.Mask")
      (net 233 "/HDMI converter/HDMI_CEC") (pinfunction "CEC") (pintype "bidirectional"))
    (pad "16" smd rect locked (at -1.2 -2.25) (size 0.23 1) (layers "F.Cu" "F.Paste" "F.Mask")
      (net 1 "GND") (pinfunction "GND") (pintype "power_in"))
    (pad "17" smd rect locked (at -1.401 -3.476) (size 0.23 0.85) (layers "F.Cu" "F.Paste" "F.Mask")
      (net 232 "/HDMI converter/HDMI_SCL") (pinfunction "SCL") (pintype "passive"))
    (pad "18" smd rect locked (at -1.601 -2.25) (size 0.23 1) (layers "F.Cu" "F.Paste" "F.Mask")
      (net 235 "/HDMI converter/HDMI_SDA") (pinfunction "SDA") (pintype "bidirectional"))
    (pad "19" smd rect locked (at -1.801 -3.476) (size 0.23 0.85) (layers "F.Cu" "F.Paste" "F.Mask")
      (net 245 "/HDMI converter/5V_HDMI") (pinfunction "+5V") (pintype "power_in"))
    (pad "SH" thru_hole oval locked (at -3.101 1.3) (size 1.05 2.1) (drill oval 0.65 1.7) (layers *.Cu *.Mask)
      (net 1 "GND") (pinfunction "SH") (pintype "passive"))
    (pad "SH" thru_hole oval locked (at 3.1 -2.061) (size 1.05 2.1) (drill oval 0.65 1.7) (layers *.Cu *.Mask)
      (net 1 "GND") (pinfunction "SH") (pintype "passive"))
    (pad "SH" thru_hole oval locked (at -3.101 -2.061) (size 1.05 2.1) (drill oval 0.65 1.7) (layers *.Cu *.Mask)
      (net 1 "GND") (pinfunction "SH") (pintype "passive"))
    (pad "SH" thru_hole oval locked (at 3.1 1.3) (size 1.05 2.1) (drill oval 0.65 1.7) (layers *.Cu *.Mask)
      (net 1 "GND") (pinfunction "SH") (pintype "passive"))
  )
	(footprint "sa800u-baseboard-hw-footprints:C_0603_1608Metric" (layer "F.Cu")
    (tedit 5D5E94D2)
    (at 77.06 108.54)
    (descr "Capacitor SMD 0603")
    (tags "capacitor 0603")
    (property "Author" "Antmicro")
    (property "Dielectric" "")
    (property "License" "Apache-2.0")
    (property "MPN" "GRM188R60J226MEA0D")
    (property "Manufacturer" "Murata")
    (property "Sheetfile" "psu.kicad_sch")
    (property "Sheetname" "PSU")
    (property "Val" "22u")
    (property "Voltage" "")
    (attr smd)
    (fp_text reference "C129" (at -3.76 0.12) (layer "F.SilkS")
      (effects (font (size 0.7 0.7) (thickness 0.15)) (justify left bottom))
    )
    (fp_text value "C_22u_0603" (at 0 1.6) (layer "F.Fab")
      (effects (font (size 0.7 0.7) (thickness 0.15)) (justify left bottom))
    )
    (fp_text user "Author: Antmicro" (at -1.682 4.894) (layer "F.Fab") hide
      (effects (font (size 0.7 0.7) (thickness 0.15)) (justify left bottom))
    )
    (fp_text user "License: Apache-2.0" (at -1.682 5.895) (layer "F.Fab") hide
      (effects (font (size 0.7 0.7) (thickness 0.15)) (justify left bottom))
    )
    (fp_text user "${REFERENCE}" (at -1.682 3.895) (layer "F.Fab") hide
      (effects (font (size 0.7 0.7) (thickness 0.15)) (justify left bottom))
    )
    (fp_line (start -0.3 -0.3) (end 0.3 -0.3) (layer "F.SilkS") (width 0.15))
    (fp_line (start -0.3 0.3) (end 0.3 0.3) (layer "F.SilkS") (width 0.15))
    (fp_rect (start -1.24 -0.7) (end 1.24 0.7) (layer "F.CrtYd") (width 0.05) (fill none))
    (fp_rect (start -0.8 -0.4) (end 0.8 0.4) (layer "F.Fab") (width 0.15) (fill none))
    (pad "1" smd roundrect (at -0.7 0) (size 0.6 0.8) (layers "F.Cu" "F.Paste" "F.Mask") (roundrect_rratio 0.2)
      (net 74 "VDD") (pintype "passive"))
    (pad "2" smd roundrect (at 0.7 0) (size 0.6 0.8) (layers "F.Cu" "F.Paste" "F.Mask") (roundrect_rratio 0.2)
      (net 1 "GND") (pintype "passive"))
  )
	(footprint "sa800u-baseboard-hw-footprints:C_0603_1608Metric" (layer "F.Cu")
    (tedit 5D5E94D2)
    (at 82.29 91.37)
    (descr "Capacitor SMD 0603")
    (tags "capacitor 0603")
    (property "Author" "Antmicro")
    (property "Dielectric" "")
    (property "License" "Apache-2.0")
    (property "MPN" "GRM188R60J226MEA0D")
    (property "Manufacturer" "Murata")
    (property "Sheetfile" "psu.kicad_sch")
    (property "Sheetname" "PSU")
    (property "Val" "22u")
    (property "Voltage" "")
    (attr smd)
    (fp_text reference "C135" (at -1.41 -2.3) (layer "F.SilkS")
      (effects (font (size 0.7 0.7) (thickness 0.15)) (justify left bottom))
    )
    (fp_text value "C_22u_0603" (at 0 1.6) (layer "F.Fab")
      (effects (font (size 0.7 0.7) (thickness 0.15)) (justify left bottom))
    )
    (fp_text user "License: Apache-2.0" (at -1.682 5.895) (layer "F.Fab") hide
      (effects (font (size 0.7 0.7) (thickness 0.15)) (justify left bottom))
    )
    (fp_text user "Author: Antmicro" (at -1.682 4.894) (layer "F.Fab") hide
      (effects (font (size 0.7 0.7) (thickness 0.15)) (justify left bottom))
    )
    (fp_text user "${REFERENCE}" (at -1.682 3.895) (layer "F.Fab") hide
      (effects (font (size 0.7 0.7) (thickness 0.15)) (justify left bottom))
    )
    (fp_line (start -0.3 -0.3) (end 0.3 -0.3) (layer "F.SilkS") (width 0.15))
    (fp_line (start -0.3 0.3) (end 0.3 0.3) (layer "F.SilkS") (width 0.15))
    (fp_rect (start -1.24 -0.7) (end 1.24 0.7) (layer "F.CrtYd") (width 0.05) (fill none))
    (fp_rect (start -0.8 -0.4) (end 0.8 0.4) (layer "F.Fab") (width 0.15) (fill none))
    (pad "1" smd roundrect (at -0.7 0) (size 0.6 0.8) (layers "F.Cu" "F.Paste" "F.Mask") (roundrect_rratio 0.2)
      (net 137 "3V8_SYS") (pintype "passive"))
    (pad "2" smd roundrect (at 0.7 0) (size 0.6 0.8) (layers "F.Cu" "F.Paste" "F.Mask") (roundrect_rratio 0.2)
      (net 1 "GND") (pintype "passive"))
  )
	(footprint "sa800u-baseboard-hw-footprints:C_0603_1608Metric" (layer "F.Cu")
    (tedit 5D5E94D2)
    (at 82.02 109.35 90)
    (descr "Capacitor SMD 0603")
    (tags "capacitor 0603")
    (property "Author" "Antmicro")
    (property "Dielectric" "")
    (property "License" "Apache-2.0")
    (property "MPN" "GRM188R60J226MEA0D")
    (property "Manufacturer" "Murata")
    (property "Sheetfile" "psu.kicad_sch")
    (property "Sheetname" "PSU")
    (property "Val" "22u")
    (property "Voltage" "")
    (attr smd)
    (fp_text reference "C136" (at -3.93 0.41 90) (layer "F.SilkS")
      (effects (font (size 0.7 0.7) (thickness 0.15)) (justify left bottom))
    )
    (fp_text value "C_22u_0603" (at 0 1.6 90) (layer "F.Fab")
      (effects (font (size 0.7 0.7) (thickness 0.15)) (justify left bottom))
    )
    (fp_text user "Author: Antmicro" (at -1.682 4.894 90) (layer "F.Fab") hide
      (effects (font (size 0.7 0.7) (thickness 0.15)) (justify left bottom))
    )
    (fp_text user "${REFERENCE}" (at -1.682 3.895 90) (layer "F.Fab") hide
      (effects (font (size 0.7 0.7) (thickness 0.15)) (justify left bottom))
    )
    (fp_text user "License: Apache-2.0" (at -1.682 5.895 90) (layer "F.Fab") hide
      (effects (font (size 0.7 0.7) (thickness 0.15)) (justify left bottom))
    )
    (fp_line (start -0.3 -0.3) (end 0.3 -0.3) (layer "F.SilkS") (width 0.15))
    (fp_line (start -0.3 0.3) (end 0.3 0.3) (layer "F.SilkS") (width 0.15))
    (fp_rect (start -1.24 -0.7) (end 1.24 0.7) (layer "F.CrtYd") (width 0.05) (fill none))
    (fp_rect (start -0.8 -0.4) (end 0.8 0.4) (layer "F.Fab") (width 0.15) (fill none))
    (pad "1" smd roundrect (at -0.7 0 90) (size 0.6 0.8) (layers "F.Cu" "F.Paste" "F.Mask") (roundrect_rratio 0.2)
      (net 131 "3V3_SYS") (pintype "passive"))
    (pad "2" smd roundrect (at 0.7 0 90) (size 0.6 0.8) (layers "F.Cu" "F.Paste" "F.Mask") (roundrect_rratio 0.2)
      (net 1 "GND") (pintype "passive"))
  )
)
